# T6G (Grand Teton) — schematic netlist excerpt (pin names and nets, part order shuffled) for the footprints in the layout excerpt that follows; sources: Cadence DE-HDL packaged netlist, KiCad conversion of 04192023_DAF0TMB3IC0_F0TG_MB_C_brd_V02_OCP.brd

PC445  Q_CAP  0.22UF 16V 10% X7R  pkg 0402  page 222 : A = SW_PVDDIO_P1_BOOT2_R ; B = SW_PVDDIO_P1_BOOTR2
R963  Q_RES  0 5% CHIP  pkg 0201LF  page 276 : A = RST_RT_CPU0_P0_RESET_N ; B = RST_RT_CPU0_P0_RESET_R_N
PC175  Q_CAP  560PF 50V 10% EMPTY  pkg C0402  page 222 : A = SW_PVDDIO_P1_SW2 ; B = SW_PVDDIO_P1_SW2_RC

(kicad_pcb
	(version 20260206)
	(generator "pcbnew")
	(generator_version "10.0")
	(general
		(thickness 1.6)
		(legacy_teardrops no)
	)
	(paper "A4")
	(title_block
		(title "04192023_DAF0TMB3IC0_F0TG_MB_C_brd_V02_OCP.brd")
		(comment 1 "Grand Teton / footprints 3290-3292 of 8354")
	)
	(layers
		(0 "F.Cu" signal "TOP")
		(4 "In1.Cu" signal "GND")
		(6 "In2.Cu" signal "IN1")
		(8 "In3.Cu" signal "GND1")
		(10 "In4.Cu" signal "IN2")
		(12 "In5.Cu" signal "GND2")
		(14 "In6.Cu" signal "IN3")
		(16 "In7.Cu" signal "GND3")
		(18 "In8.Cu" signal "VCC")
		(20 "In9.Cu" signal "VCC1")
		(22 "In10.Cu" signal "GND4")
		(24 "In11.Cu" signal "IN4")
		(26 "In12.Cu" signal "GND5")
		(28 "In13.Cu" signal "IN5")
		(30 "In14.Cu" signal "GND6")
		(32 "In15.Cu" signal "IN6")
		(34 "In16.Cu" signal "GND7")
		(2 "B.Cu" signal "BOTTOM")
		(9 "F.Adhes" user "F.Adhesive")
		(11 "B.Adhes" user "B.Adhesive")
		(13 "F.Paste" user "Package Geometry/Pastemask Top")
		(15 "B.Paste" user "Package Geometry/Pastemask Bottom")
		(5 "F.SilkS" user "Ref Des/Silkscreen Top")
		(7 "B.SilkS" user "Ref Des/Silkscreen Bottom")
		(1 "F.Mask" user "Board Geometry/Soldermask Top")
		(3 "B.Mask" user "Board Geometry/Soldermask Bottom")
		(17 "Dwgs.User" user "User.Drawings")
		(19 "Cmts.User" user "User.Comments")
		(21 "Eco1.User" user "User.Eco1")
		(23 "Eco2.User" user "User.Eco2")
		(25 "Edge.Cuts" user "Board Geometry/Outline")
		(27 "Margin" user)
		(31 "F.CrtYd" user "Package Geometry/Place Bound Top")
		(29 "B.CrtYd" user "Package Geometry/Place Bound Bottom")
		(35 "F.Fab" user "Ref Des/Assembly Top")
		(33 "B.Fab" user "Ref Des/Assembly Bottom")
	)
	(footprint ""
		(layer "F.Cu")
		(at 41.492932 -343.716864 180)
		(property "Reference" "PC175"
			(at 0 0 180)
			(layer "F.SilkS")
			(hide yes)
			(effects
				(font
					(size 1.27 1.27)
				)
			)
		)
		(property "Value" ""
			(at 0 0 180)
			(layer "F.Fab")
			(effects
				(font
					(size 1.27 1.27)
				)
			)
		)
		(duplicate_pad_numbers_are_jumpers no)
		(fp_line
			(start 0.7874 0.4064)
			(end -0.7874 0.4064)
			(stroke
				(width 0.1524)
				(type default)
			)
			(layer "F.SilkS")
		)
		(fp_line
			(start 0.7874 -0.4064)
			(end 0.7874 0.4064)
			(stroke
				(width 0.1524)
				(type default)
			)
			(layer "F.SilkS")
		)
		(fp_line
			(start -0.7874 0.4064)
			(end -0.7874 -0.4064)
			(stroke
				(width 0.1524)
				(type default)
			)
			(layer "F.SilkS")
		)
		(fp_line
			(start -0.7874 -0.4064)
			(end 0.7874 -0.4064)
			(stroke
				(width 0.1524)
				(type default)
			)
			(layer "F.SilkS")
		)
		(fp_line
			(start 0.67945 0.3048)
			(end 0.120396 0.3048)
			(stroke
				(width 0.1)
				(type default)
			)
			(layer "F.Fab")
		)
		(fp_line
			(start 0.67945 -0.3048)
			(end 0.67945 0.3048)
			(stroke
				(width 0.1)
				(type default)
			)
			(layer "F.Fab")
		)
		(fp_line
			(start 0.12065 -0.2794)
			(end 0.12065 -0.3048)
			(stroke
				(width 0.1)
				(type default)
			)
			(layer "F.Fab")
		)
		(fp_line
			(start 0.12065 -0.3048)
			(end 0.67945 -0.3048)
			(stroke
				(width 0.1)
				(type default)
			)
			(layer "F.Fab")
		)
		(fp_line
			(start 0.120396 0.3048)
			(end 0.120396 0.2794)
			(stroke
				(width 0.1)
				(type default)
			)
			(layer "F.Fab")
		)
		(fp_line
			(start 0.120396 0.2794)
			(end -0.12065 0.2794)
			(stroke
				(width 0.1)
				(type default)
			)
			(layer "F.Fab")
		)
		(fp_line
			(start -0.12065 0.3048)
			(end -0.67945 0.3048)
			(stroke
				(width 0.1)
				(type default)
			)
			(layer "F.Fab")
		)
		(fp_line
			(start -0.12065 0.2794)
			(end -0.12065 0.3048)
			(stroke
				(width 0.1)
				(type default)
			)
			(layer "F.Fab")
		)
		(fp_line
			(start -0.12065 -0.2794)
			(end 0.12065 -0.2794)
			(stroke
				(width 0.1)
				(type default)
			)
			(layer "F.Fab")
		)
		(fp_line
			(start -0.12065 -0.305054)
			(end -0.12065 -0.2794)
			(stroke
				(width 0.1)
				(type default)
			)
			(layer "F.Fab")
		)
		(fp_line
			(start -0.67945 0.3048)
			(end -0.67945 -0.305054)
			(stroke
				(width 0.1)
				(type default)
			)
			(layer "F.Fab")
		)
		(fp_line
			(start -0.67945 -0.305054)
			(end -0.12065 -0.305054)
			(stroke
				(width 0.1)
				(type default)
			)
			(layer "F.Fab")
		)
		(pad "1" smd circle
			(at -0.40005 0 180)
			(size 0 0)
			(layers "F.Cu" "F.Mask" "F.Paste")
			(net "SW_PVDDIO_P1_SW2")
		)
		(pad "2" smd circle
			(at 0.40005 0 180)
			(size 0 0)
			(layers "F.Cu" "F.Mask" "F.Paste")
			(net "SW_PVDDIO_P1_SW2_RC")
		)
	)
	(footprint ""
		(layer "F.Cu")
		(at 297.554142 -398.2212 180)
		(property "Reference" "R963"
			(at 0 0 180)
			(layer "F.SilkS")
			(hide yes)
			(effects
				(font
					(size 1.27 1.27)
				)
			)
		)
		(property "Value" ""
			(at 0 0 180)
			(layer "F.Fab")
			(effects
				(font
					(size 1.27 1.27)
				)
			)
		)
		(duplicate_pad_numbers_are_jumpers no)
		(fp_line
			(start 0.32512 0.175006)
			(end -0.32512 0.175006)
			(stroke
				(width 0.1)
				(type default)
			)
			(layer "F.Fab")
		)
		(fp_line
			(start 0.32512 -0.175006)
			(end 0.32512 0.175006)
			(stroke
				(width 0.1)
				(type default)
			)
			(layer "F.Fab")
		)
		(fp_line
			(start -0.32512 0.175006)
			(end -0.32512 -0.175006)
			(stroke
				(width 0.1)
				(type default)
			)
			(layer "F.Fab")
		)
		(fp_line
			(start -0.32512 -0.175006)
			(end 0.32512 -0.175006)
			(stroke
				(width 0.1)
				(type default)
			)
			(layer "F.Fab")
		)
		(pad "1" smd rect
			(at -0.2667 0 180)
			(size 0.3048 0.381)
			(layers "F.Cu" "F.Mask" "F.Paste")
			(net "RST_RT_CPU0_P0_RESET_N")
		)
		(pad "2" smd rect
			(at 0.2667 0)
			(size 0.3048 0.381)
			(layers "F.Cu" "F.Mask" "F.Paste")
			(net "RST_RT_CPU0_P0_RESET_R_N")
		)
	)
	(footprint ""
		(layer "F.Cu")
		(at 46.972728 -351.372932 -90)
		(property "Reference" "PC445"
			(at 0 0 270)
			(layer "F.SilkS")
			(hide yes)
			(effects
				(font
					(size 1.27 1.27)
				)
			)
		)
		(property "Value" ""
			(at 0 0 270)
			(layer "F.Fab")
			(effects
				(font
					(size 1.27 1.27)
				)
			)
		)
		(duplicate_pad_numbers_are_jumpers no)
		(fp_line
			(start -0.7874 0.4064)
			(end -0.7874 -0.4064)
			(stroke
				(width 0.1524)
				(type default)
			)
			(layer "F.SilkS")
		)
		(fp_line
			(start 0.7874 0.4064)
			(end -0.7874 0.4064)
			(stroke
				(width 0.1524)
				(type default)
			)
			(layer "F.SilkS")
		)
		(fp_line
			(start -0.7874 -0.4064)
			(end 0.7874 -0.4064)
			(stroke
				(width 0.1524)
				(type default)
			)
			(layer "F.SilkS")
		)
		(fp_line
			(start 0.7874 -0.4064)
			(end 0.7874 0.4064)
			(stroke
				(width 0.1524)
				(type default)
			)
			(layer "F.SilkS")
		)
		(fp_line
			(start -0.67945 0.3048)
			(end -0.67945 -0.305054)
			(stroke
				(width 0.1)
				(type default)
			)
			(layer "F.Fab")
		)
		(fp_line
			(start -0.12065 0.3048)
			(end -0.67945 0.3048)
			(stroke
				(width 0.1)
				(type default)
			)
			(layer "F.Fab")
		)
		(fp_line
			(start 0.120396 0.3048)
			(end 0.120396 0.2794)
			(stroke
				(width 0.1)
				(type default)
			)
			(layer "F.Fab")
		)
		(fp_line
			(start 0.67945 0.3048)
			(end 0.120396 0.3048)
			(stroke
				(width 0.1)
				(type default)
			)
			(layer "F.Fab")
		)
		(fp_line
			(start -0.12065 0.2794)
			(end -0.12065 0.3048)
			(stroke
				(width 0.1)
				(type default)
			)
			(layer "F.Fab")
		)
		(fp_line
			(start 0.120396 0.2794)
			(end -0.12065 0.2794)
			(stroke
				(width 0.1)
				(type default)
			)
			(layer "F.Fab")
		)
		(fp_line
			(start -0.12065 -0.2794)
			(end 0.12065 -0.2794)
			(stroke
				(width 0.1)
				(type default)
			)
			(layer "F.Fab")
		)
		(fp_line
			(start 0.12065 -0.2794)
			(end 0.12065 -0.3048)
			(stroke
				(width 0.1)
				(type default)
			)
			(layer "F.Fab")
		)
		(fp_line
			(start 0.12065 -0.3048)
			(end 0.67945 -0.3048)
			(stroke
				(width 0.1)
				(type default)
			)
			(layer "F.Fab")
		)
		(fp_line
			(start 0.67945 -0.3048)
			(end 0.67945 0.3048)
			(stroke
				(width 0.1)
				(type default)
			)
			(layer "F.Fab")
		)
		(fp_line
			(start -0.67945 -0.305054)
			(end -0.12065 -0.305054)
			(stroke
				(width 0.1)
				(type default)
			)
			(layer "F.Fab")
		)
		(fp_line
			(start -0.12065 -0.305054)
			(end -0.12065 -0.2794)
			(stroke
				(width 0.1)
				(type default)
			)
			(layer "F.Fab")
		)
		(pad "1" smd circle
			(at -0.40005 0 270)
			(size 0 0)
			(layers "F.Cu" "F.Mask" "F.Paste")
			(net "SW_PVDDIO_P1_BOOT2_R")
		)
		(pad "2" smd circle
			(at 0.40005 0 270)
			(size 0 0)
			(layers "F.Cu" "F.Mask" "F.Paste")
			(net "SW_PVDDIO_P1_BOOTR2")
		)
	)
)
